(kicad_pcb
	(version 20241229)
	(generator "pcbnew")
	(generator_version "9.0")
	(general
		(thickness 1.6296)
		(legacy_teardrops no)
	)
	(paper "A3")
	(title_block
		(title "Thunderbolt to 10GbE adapter")
		(date "2026-04-21")
		(rev "1.1.0")
		(company "Antmicro Ltd")
		(comment 1 "www.antmicro.com")
		(comment 9 "footprints 338-342 of 703")
	)
	(layers
		(0 "F.Cu" signal)
		(4 "In1.Cu" signal)
		(6 "In2.Cu" signal)
		(8 "In3.Cu" signal)
		(10 "In4.Cu" signal)
		(12 "In5.Cu" signal)
		(14 "In6.Cu" signal)
		(2 "B.Cu" signal)
		(9 "F.Adhes" user "F.Adhesive")
		(11 "B.Adhes" user "B.Adhesive")
		(13 "F.Paste" user)
		(15 "B.Paste" user)
		(5 "F.SilkS" user "F.Silkscreen")
		(7 "B.SilkS" user "B.Silkscreen")
		(1 "F.Mask" user)
		(3 "B.Mask" user)
		(17 "Dwgs.User" user "User.Drawings")
		(19 "Cmts.User" user "User.Comments")
		(21 "Eco1.User" user "User.Eco1")
		(23 "Eco2.User" user "User.Eco2")
		(25 "Edge.Cuts" user)
		(27 "Margin" user)
		(31 "F.CrtYd" user "F.Courtyard")
		(29 "B.CrtYd" user "B.Courtyard")
		(35 "F.Fab" user)
		(33 "B.Fab" user)
	)
	(footprint "antmicro-footprints:R_0603_1608Metric"
		(layer "F.Cu")
		(at 116.65 111.25 90)
		(descr "Resistor SMD 0603")
		(tags "resistor SMD 0603")
		(property "Reference" "R3"
			(at 0 -1.05 90)
			(layer "F.SilkS")
			(effects
				(font
					(size 0.7 0.7)
					(thickness 0.15)
				)
			)
		)
		(property "Value" "R_0R_22.4A_0603"
			(at 0 1.6 90)
			(layer "F.Fab")
			(effects
				(font
					(size 0.7 0.7)
					(thickness 0.15)
				)
				(justify left bottom)
			)
		)
		(property "Datasheet" "https://fscdn.rohm.com/en/products/databook/datasheet/passive/resistor/chip_resistor/pmr-jpw-e.pdf"
			(at 0 0 90)
			(layer "F.Fab")
			(hide yes)
			(effects
				(font
					(size 1.27 1.27)
					(thickness 0.15)
				)
			)
		)
		(property "Description" "SMD Chip Resistor"
			(at 0 0 90)
			(layer "F.Fab")
			(hide yes)
			(effects
				(font
					(size 1.27 1.27)
					(thickness 0.15)
				)
			)
		)
		(property "MPN" "PMR03EZPJ000"
			(at 0 0 90)
			(unlocked yes)
			(layer "F.Fab")
			(hide yes)
			(effects
				(font
					(size 1 1)
					(thickness 0.15)
				)
			)
		)
		(property "Manufacturer" "ROHM Semiconductor"
			(at 0 0 90)
			(unlocked yes)
			(layer "F.Fab")
			(hide yes)
			(effects
				(font
					(size 1 1)
					(thickness 0.15)
				)
			)
		)
		(property "Val" "0R"
			(at 0 0 90)
			(unlocked yes)
			(layer "F.Fab")
			(hide yes)
			(effects
				(font
					(size 1 1)
					(thickness 0.15)
				)
			)
		)
		(property "Max. Curr." "22.4A"
			(at 0 0 90)
			(unlocked yes)
			(layer "F.Fab")
			(hide yes)
			(effects
				(font
					(size 1 1)
					(thickness 0.15)
				)
			)
		)
		(property "Author" "Antmicro"
			(at 0 0 90)
			(unlocked yes)
			(layer "F.Fab")
			(hide yes)
			(effects
				(font
					(size 1 1)
					(thickness 0.15)
				)
			)
		)
		(property "License" "Apache-2.0"
			(at 0 0 90)
			(unlocked yes)
			(layer "F.Fab")
			(hide yes)
			(effects
				(font
					(size 1 1)
					(thickness 0.15)
				)
			)
		)
		(property "Tolerance" "template_tolerance"
			(at 0 0 90)
			(unlocked yes)
			(layer "F.Fab")
			(hide yes)
			(effects
				(font
					(size 1 1)
					(thickness 0.15)
				)
			)
		)
		(sheetname "/PD and TB DC-DC/")
		(sheetfile "PD_and_TB_DC_DC.kicad_sch")
		(attr smd)
		(fp_line
			(start -0.15 -0.4)
			(end 0.15 -0.4)
			(stroke
				(width 0.15)
				(type solid)
			)
			(layer "F.SilkS")
		)
		(fp_line
			(start -0.15 0.4)
			(end 0.15 0.4)
			(stroke
				(width 0.15)
				(type solid)
			)
			(layer "F.SilkS")
		)
		(fp_rect
			(start -1.25 -0.65)
			(end 1.25 0.65)
			(stroke
				(width 0.05)
				(type solid)
			)
			(fill no)
			(layer "F.CrtYd")
		)
		(fp_rect
			(start -0.8 -0.4)
			(end 0.8 0.4)
			(stroke
				(width 0.15)
				(type solid)
			)
			(fill no)
			(layer "F.Fab")
		)
		(fp_text user "${REFERENCE}"
			(at -1.25 3.898 90)
			(layer "F.Fab")
			(effects
				(font
					(size 0.7 0.7)
					(thickness 0.15)
				)
				(justify left bottom)
			)
		)
		(fp_text user "License: Apache-2.0"
			(at -1.25 5.9 90)
			(layer "F.Fab")
			(effects
				(font
					(size 0.7 0.7)
					(thickness 0.15)
				)
				(justify left bottom)
			)
		)
		(fp_text user "Author: Antmicro"
			(at -1.25 4.9 90)
			(layer "F.Fab")
			(effects
				(font
					(size 0.7 0.7)
					(thickness 0.15)
				)
				(justify left bottom)
			)
		)
		(pad "1" smd roundrect
			(at -0.7 0 90)
			(size 0.8 1)
			(layers "F.Cu" "F.Mask" "F.Paste")
			(roundrect_rratio 0.2)
			(net 53 "+5V_USB")
			(pintype "passive")
		)
		(pad "2" smd roundrect
			(at 0.7 0 90)
			(size 0.8 1)
			(layers "F.Cu" "F.Mask" "F.Paste")
			(roundrect_rratio 0.2)
			(net 161 "Net-(U2-VIN)")
			(pintype "passive")
		)
	)
	(footprint "antmicro-footprints:C_0402_1005Metric"
		(layer "F.Cu")
		(at 130.2 71.4 180)
		(descr "Capacitor SMD 0402")
		(tags "capacitor SMD 0402")
		(property "Reference" "C310"
			(at 1 2 180)
			(layer "F.SilkS")
			(effects
				(font
					(size 0.7 0.7)
					(thickness 0.15)
				)
				(justify left bottom)
			)
		)
		(property "Value" "C_100n_0402"
			(at -1.022927 2.155213 180)
			(layer "F.Fab")
			(effects
				(font
					(size 0.7 0.7)
					(thickness 0.15)
				)
				(justify left bottom)
			)
		)
		(property "Datasheet" "https://www.murata.com/products/productdetail?partno=GRM155R61H104KE14%23"
			(at 0 0 180)
			(layer "F.Fab")
			(hide yes)
			(effects
				(font
					(size 1.27 1.27)
					(thickness 0.15)
				)
			)
		)
		(property "Description" "SMD Multilayer Ceramic Capacitor, 0.1 µF, 50 V, 0402 [1005 Metric], ± 10%, X5R, GRM Series"
			(at 0 0 180)
			(layer "F.Fab")
			(hide yes)
			(effects
				(font
					(size 1.27 1.27)
					(thickness 0.15)
				)
			)
		)
		(property "MPN" "GRM155R61H104KE14D"
			(at 0 0 180)
			(unlocked yes)
			(layer "F.Fab")
			(hide yes)
			(effects
				(font
					(size 1 1)
					(thickness 0.15)
				)
			)
		)
		(property "Val" "100n"
			(at 0 0 180)
			(unlocked yes)
			(layer "F.Fab")
			(hide yes)
			(effects
				(font
					(size 1 1)
					(thickness 0.15)
				)
			)
		)
		(property "Voltage" "50V"
			(at 0 0 180)
			(unlocked yes)
			(layer "F.Fab")
			(hide yes)
			(effects
				(font
					(size 1 1)
					(thickness 0.15)
				)
			)
		)
		(property "Dielectric" "X5R"
			(at 0 0 180)
			(unlocked yes)
			(layer "F.Fab")
			(hide yes)
			(effects
				(font
					(size 1 1)
					(thickness 0.15)
				)
			)
		)
		(property "Manufacturer" "Murata"
			(at 0 0 180)
			(unlocked yes)
			(layer "F.Fab")
			(hide yes)
			(effects
				(font
					(size 1 1)
					(thickness 0.15)
				)
			)
		)
		(property "License" "Apache-2.0"
			(at 0 0 180)
			(unlocked yes)
			(layer "F.Fab")
			(hide yes)
			(effects
				(font
					(size 1 1)
					(thickness 0.15)
				)
			)
		)
		(property "Author" "Antmicro"
			(at 0 0 180)
			(unlocked yes)
			(layer "F.Fab")
			(hide yes)
			(effects
				(font
					(size 1 1)
					(thickness 0.15)
				)
			)
		)
		(sheetname "/X710 flash memory/")
		(sheetfile "flash_x710.kicad_sch")
		(attr smd)
		(fp_rect
			(start -0.925 -0.47)
			(end 0.925 0.47)
			(stroke
				(width 0.05)
				(type default)
			)
			(fill no)
			(layer "F.CrtYd")
		)
		(fp_line
			(start 0.504 0.248)
			(end -0.494 0.248)
			(stroke
				(width 0.15)
				(type solid)
			)
			(layer "F.Fab")
		)
		(fp_line
			(start 0.504 -0.25)
			(end 0.504 0.248)
			(stroke
				(width 0.15)
				(type solid)
			)
			(layer "F.Fab")
		)
		(fp_line
			(start -0.494 0.248)
			(end -0.494 -0.25)
			(stroke
				(width 0.15)
				(type solid)
			)
			(layer "F.Fab")
		)
		(fp_line
			(start -0.494 -0.25)
			(end 0.504 -0.25)
			(stroke
				(width 0.15)
				(type solid)
			)
			(layer "F.Fab")
		)
		(fp_text user "${REFERENCE}"
			(at -0.939 4.599 180)
			(layer "F.Fab")
			(effects
				(font
					(size 0.7 0.7)
					(thickness 0.15)
				)
				(justify left bottom)
			)
		)
		(fp_text user "License: Apache-2.0"
			(at -0.939 5.799 180)
			(layer "F.Fab")
			(effects
				(font
					(size 0.7 0.7)
					(thickness 0.15)
				)
				(justify left bottom)
			)
		)
		(fp_text user "Author: Antmicro"
			(at -0.939 3.399 180)
			(layer "F.Fab")
			(effects
				(font
					(size 0.7 0.7)
					(thickness 0.15)
				)
				(justify left bottom)
			)
		)
		(pad "1" smd roundrect
			(at -0.48 0 180)
			(size 0.59 0.64)
			(layers "F.Cu" "F.Mask" "F.Paste")
			(roundrect_rratio 0.25)
			(net 23 "GND")
			(pintype "passive")
		)
		(pad "2" smd roundrect
			(at 0.48 0 180)
			(size 0.59 0.64)
			(layers "F.Cu" "F.Mask" "F.Paste")
			(roundrect_rratio 0.25)
			(net 343 "/X710 flash memory/+3V3_FLASH")
			(pintype "passive")
		)
	)
	(footprint "antmicro-footprints:C_0603_1608Metric_EIA"
		(layer "F.Cu")
		(at 147.2 114.35)
		(descr "Capacitor SMD 0603, IPC-7351 Density Level A")
		(tags "Capacitor 0603")
		(property "Reference" "C113"
			(at 14.850002 16.550003 0)
			(layer "F.SilkS")
			(effects
				(font
					(size 0.7 0.7)
					(thickness 0.15)
				)
			)
		)
		(property "Value" "C_22u_16V_0603"
			(at -1.42757 1.770288 0)
			(layer "F.Fab")
			(effects
				(font
					(size 0.7 0.7)
					(thickness 0.15)
				)
				(justify left bottom)
			)
		)
		(property "Datasheet" "https://product.samsungsem.com/mlcc/CL10A226MO7JZN.do"
			(at 0 0 0)
			(layer "F.Fab")
			(hide yes)
			(effects
				(font
					(size 1.27 1.27)
					(thickness 0.15)
				)
			)
		)
		(property "Description" "SMD Multilayer Ceramic Capacitor"
			(at 0 0 0)
			(layer "F.Fab")
			(hide yes)
			(effects
				(font
					(size 1.27 1.27)
					(thickness 0.15)
				)
			)
		)
		(property "MPN" "CL10A226MO7JZNC"
			(at 0 0 0)
			(unlocked yes)
			(layer "F.Fab")
			(hide yes)
			(effects
				(font
					(size 1 1)
					(thickness 0.15)
				)
			)
		)
		(property "Manufacturer" "Samsung Electro-Mechanics"
			(at 0 0 0)
			(unlocked yes)
			(layer "F.Fab")
			(hide yes)
			(effects
				(font
					(size 1 1)
					(thickness 0.15)
				)
			)
		)
		(property "License" "Apache-2.0"
			(at 0 0 0)
			(unlocked yes)
			(layer "F.Fab")
			(hide yes)
			(effects
				(font
					(size 1 1)
					(thickness 0.15)
				)
			)
		)
		(property "Author" "Antmicro"
			(at 0 0 0)
			(unlocked yes)
			(layer "F.Fab")
			(hide yes)
			(effects
				(font
					(size 1 1)
					(thickness 0.15)
				)
			)
		)
		(property "Val" "22u"
			(at 0 0 0)
			(unlocked yes)
			(layer "F.Fab")
			(hide yes)
			(effects
				(font
					(size 1 1)
					(thickness 0.15)
				)
			)
		)
		(property "Voltage" "16V"
			(at 0 0 0)
			(unlocked yes)
			(layer "F.Fab")
			(hide yes)
			(effects
				(font
					(size 1 1)
					(thickness 0.15)
				)
			)
		)
		(property "Dielectric" ""
			(at 0 0 0)
			(unlocked yes)
			(layer "F.Fab")
			(hide yes)
			(effects
				(font
					(size 1 1)
					(thickness 0.15)
				)
			)
		)
		(sheetname "/X710 DCDC converters/")
		(sheetfile "DCDC_converters_X710.kicad_sch")
		(attr smd)
		(fp_line
			(start -0.15 -0.55)
			(end 0.15 -0.55)
			(stroke
				(width 0.15)
				(type solid)
			)
			(layer "F.SilkS")
		)
		(fp_line
			(start -0.15 0.55)
			(end 0.15 0.55)
			(stroke
				(width 0.15)
				(type solid)
			)
			(layer "F.SilkS")
		)
		(fp_rect
			(start -1.25 -0.65)
			(end 1.25 0.65)
			(stroke
				(width 0.05)
				(type solid)
			)
			(fill no)
			(layer "F.CrtYd")
		)
		(fp_rect
			(start -0.8 -0.45)
			(end 0.8 0.45)
			(stroke
				(width 0.15)
				(type solid)
			)
			(fill no)
			(layer "F.Fab")
		)
		(fp_text user "${REFERENCE}"
			(at -1.682 3.895 0)
			(layer "F.Fab")
			(effects
				(font
					(size 0.7 0.7)
					(thickness 0.15)
				)
				(justify left bottom)
			)
		)
		(fp_text user "Author: Antmicro"
			(at -1.682 4.894 0)
			(layer "F.Fab")
			(effects
				(font
					(size 0.7 0.7)
					(thickness 0.15)
				)
				(justify left bottom)
			)
		)
		(fp_text user "License: Apache-2.0"
			(at -1.682 5.895 0)
			(layer "F.Fab")
			(effects
				(font
					(size 0.7 0.7)
					(thickness 0.15)
				)
				(justify left bottom)
			)
		)
		(pad "1" smd roundrect
			(at -0.7 0)
			(size 0.8 1.1)
			(layers "F.Cu" "F.Mask" "F.Paste")
			(roundrect_rratio 0.2)
			(net 23 "GND")
			(pintype "passive")
		)
		(pad "2" smd roundrect
			(at 0.7 0)
			(size 0.8 1.1)
			(layers "F.Cu" "F.Mask" "F.Paste")
			(roundrect_rratio 0.2)
			(net 40 "+5V")
			(pintype "passive")
		)
	)
	(footprint "antmicro-footprints:C_0402_1005Metric"
		(layer "F.Cu")
		(at 138 73.25)
		(descr "Capacitor SMD 0402")
		(tags "capacitor SMD 0402")
		(property "Reference" "C266"
			(at -3.8 0.45 0)
			(layer "F.SilkS")
			(effects
				(font
					(size 0.7 0.7)
					(thickness 0.15)
				)
				(justify left bottom)
			)
		)
		(property "Value" "C_220n_16V_0402"
			(at -1.022927 2.155213 0)
			(layer "F.Fab")
			(effects
				(font
					(size 0.7 0.7)
					(thickness 0.15)
				)
				(justify left bottom)
			)
		)
		(property "Datasheet" "https://www.murata.com/products/productdetail?partno=GRM155R71C224KA12%23"
			(at 0 0 0)
			(layer "F.Fab")
			(hide yes)
			(effects
				(font
					(size 1.27 1.27)
					(thickness 0.15)
				)
			)
		)
		(property "Description" "SMD Multilayer Ceramic Capacitor, 0.22 µF, 16 V, 0402 [1005 Metric], ± 10%, X7R, GRM Series"
			(at 0 0 0)
			(layer "F.Fab")
			(hide yes)
			(effects
				(font
					(size 1.27 1.27)
					(thickness 0.15)
				)
			)
		)
		(property "MPN" "GRM155R71C224KA12D"
			(at 0 0 0)
			(unlocked yes)
			(layer "F.Fab")
			(hide yes)
			(effects
				(font
					(size 1 1)
					(thickness 0.15)
				)
			)
		)
		(property "Manufacturer" "Murata"
			(at 0 0 0)
			(unlocked yes)
			(layer "F.Fab")
			(hide yes)
			(effects
				(font
					(size 1 1)
					(thickness 0.15)
				)
			)
		)
		(property "License" "Apache-2.0"
			(at 0 0 0)
			(unlocked yes)
			(layer "F.Fab")
			(hide yes)
			(effects
				(font
					(size 1 1)
					(thickness 0.15)
				)
			)
		)
		(property "Author" "Antmicro"
			(at 0 0 0)
			(unlocked yes)
			(layer "F.Fab")
			(hide yes)
			(effects
				(font
					(size 1 1)
					(thickness 0.15)
				)
			)
		)
		(property "Val" "220n"
			(at 0 0 0)
			(unlocked yes)
			(layer "F.Fab")
			(hide yes)
			(effects
				(font
					(size 1 1)
					(thickness 0.15)
				)
			)
		)
		(property "Voltage" "16V"
			(at 0 0 0)
			(unlocked yes)
			(layer "F.Fab")
			(hide yes)
			(effects
				(font
					(size 1 1)
					(thickness 0.15)
				)
			)
		)
		(property "Dielectric" "X7R"
			(at 0 0 0)
			(unlocked yes)
			(layer "F.Fab")
			(hide yes)
			(effects
				(font
					(size 1 1)
					(thickness 0.15)
				)
			)
		)
		(sheetname "/X710-AT2 PCIe/")
		(sheetfile "x710-at2-pcie.kicad_sch")
		(attr smd)
		(fp_rect
			(start -0.925 -0.47)
			(end 0.925 0.47)
			(stroke
				(width 0.05)
				(type default)
			)
			(fill no)
			(layer "F.CrtYd")
		)
		(fp_line
			(start -0.494 -0.25)
			(end 0.504 -0.25)
			(stroke
				(width 0.15)
				(type solid)
			)
			(layer "F.Fab")
		)
		(fp_line
			(start -0.494 0.248)
			(end -0.494 -0.25)
			(stroke
				(width 0.15)
				(type solid)
			)
			(layer "F.Fab")
		)
		(fp_line
			(start 0.504 -0.25)
			(end 0.504 0.248)
			(stroke
				(width 0.15)
				(type solid)
			)
			(layer "F.Fab")
		)
		(fp_line
			(start 0.504 0.248)
			(end -0.494 0.248)
			(stroke
				(width 0.15)
				(type solid)
			)
			(layer "F.Fab")
		)
		(fp_text user "${REFERENCE}"
			(at -0.939 4.599 0)
			(layer "F.Fab")
			(effects
				(font
					(size 0.7 0.7)
					(thickness 0.15)
				)
				(justify left bottom)
			)
		)
		(fp_text user "Author: Antmicro"
			(at -0.939 3.399 0)
			(layer "F.Fab")
			(effects
				(font
					(size 0.7 0.7)
					(thickness 0.15)
				)
				(justify left bottom)
			)
		)
		(fp_text user "License: Apache-2.0"
			(at -0.939 5.799 0)
			(layer "F.Fab")
			(effects
				(font
					(size 0.7 0.7)
					(thickness 0.15)
				)
				(justify left bottom)
			)
		)
		(pad "1" smd roundrect
			(at -0.48 0)
			(size 0.59 0.64)
			(layers "F.Cu" "F.Mask" "F.Paste")
			(roundrect_rratio 0.25)
			(net 597 "/TB Controller/PCIex4.TX0-")
			(pintype "passive")
		)
		(pad "2" smd roundrect
			(at 0.48 0)
			(size 0.59 0.64)
			(layers "F.Cu" "F.Mask" "F.Paste")
			(roundrect_rratio 0.25)
			(net 28 "/X710-AT2 PCIe/PCIe_{x4}_AC.TX0-")
			(pintype "passive")
		)
	)
	(footprint "antmicro-footprints:R_0402_1005Metric"
		(layer "F.Cu")
		(at 161.104999 67.124999 -90)
		(descr "Resistor SMD 0402")
		(tags "resistor SMD 0402")
		(property "Reference" "R193"
			(at -12.324999 -20.295 270)
			(layer "F.SilkS")
			(effects
				(font
					(size 0.7 0.7)
					(thickness 0.15)
				)
			)
		)
		(property "Value" "R_150R_0402"
			(at -1.011843 1.772047 270)
			(layer "F.Fab")
			(effects
				(font
					(size 0.7 0.7)
					(thickness 0.15)
				)
				(justify left bottom)
			)
		)
		(property "Datasheet" "https://www.bourns.com/docs/product-datasheets/cr.pdf"
			(at 0 0 270)
			(layer "F.Fab")
			(hide yes)
			(effects
				(font
					(size 1.27 1.27)
					(thickness 0.15)
				)
			)
		)
		(property "Description" "SMD Chip Resistor, 150 ohm, ± 1%, 62.5 mW, 0402 [1005 Metric], Thick Film, General Purpose"
			(at 0 0 270)
			(layer "F.Fab")
			(hide yes)
			(effects
				(font
					(size 1.27 1.27)
					(thickness 0.15)
				)
			)
		)
		(property "MPN" "CR0402-FX-1500GLF"
			(at 0 0 270)
			(unlocked yes)
			(layer "F.Fab")
			(hide yes)
			(effects
				(font
					(size 1 1)
					(thickness 0.15)
				)
			)
		)
		(property "Manufacturer" "Bourns"
			(at 0 0 270)
			(unlocked yes)
			(layer "F.Fab")
			(hide yes)
			(effects
				(font
					(size 1 1)
					(thickness 0.15)
				)
			)
		)
		(property "License" "Apache-2.0"
			(at 0 0 270)
			(unlocked yes)
			(layer "F.Fab")
			(hide yes)
			(effects
				(font
					(size 1 1)
					(thickness 0.15)
				)
			)
		)
		(property "Author" "Antmicro"
			(at 0 0 270)
			(unlocked yes)
			(layer "F.Fab")
			(hide yes)
			(effects
				(font
					(size 1 1)
					(thickness 0.15)
				)
			)
		)
		(property "Val" "150R"
			(at 0 0 270)
			(unlocked yes)
			(layer "F.Fab")
			(hide yes)
			(effects
				(font
					(size 1 1)
					(thickness 0.15)
				)
			)
		)
		(property "Tolerance" "1%"
			(at 0 0 270)
			(unlocked yes)
			(layer "F.Fab")
			(hide yes)
			(effects
				(font
					(size 1 1)
					(thickness 0.15)
				)
			)
		)
		(sheetname "/X710-AT2 10GbE/")
		(sheetfile "x710-at2-10gbe.kicad_sch")
		(attr smd)
		(fp_rect
			(start -0.925 -0.47)
			(end 0.925 0.47)
			(stroke
				(width 0.05)
				(type default)
			)
			(fill no)
			(layer "F.CrtYd")
		)
		(fp_rect
			(start -0.5 -0.25)
			(end 0.5 0.25)
			(stroke
				(width 0.15)
				(type solid)
			)
			(fill no)
			(layer "F.Fab")
		)
		(fp_text user "${REFERENCE}"
			(at -0.95 3.168 270)
			(layer "F.Fab")
			(effects
				(font
					(size 0.7 0.7)
					(thickness 0.15)
				)
				(justify left bottom)
			)
		)
		(fp_text user "License: Apache-2.0"
			(at -0.95 5.169 270)
			(layer "F.Fab")
			(effects
				(font
					(size 0.7 0.7)
					(thickness 0.15)
				)
				(justify left bottom)
			)
		)
		(fp_text user "Author: Antmicro"
			(at -0.95 4.169 270)
			(layer "F.Fab")
			(effects
				(font
					(size 0.7 0.7)
					(thickness 0.15)
				)
				(justify left bottom)
			)
		)
		(pad "1" smd roundrect
			(at -0.48 0 270)
			(size 0.59 0.64)
			(layers "F.Cu" "F.Mask" "F.Paste")
			(roundrect_rratio 0.25)
			(net 23 "GND")
			(pintype "passive")
		)
		(pad "2" smd roundrect
			(at 0.48 0 270)
			(size 0.59 0.64)
			(layers "F.Cu" "F.Mask" "F.Paste")
			(roundrect_rratio 0.25)
			(net 55 "/X710-AT2 10GbE/25MHZ_OSC_AC.-")
			(pintype "passive")
		)
	)
)
